(kicad_pcb
	(version 20260206)
	(generator "pcbnew")
	(generator_version "10.0")
	(general
		(thickness 1.6)
		(legacy_teardrops no)
	)
	(paper "A4")
	(title_block
		(title "04192023_DAF0TMB3IC0_F0TG_MB_C_brd_V02_OCP.brd")
		(comment 1 "Grand Teton / footprints 6369-6375 of 8354")
	)
	(layers
		(0 "F.Cu" signal "TOP")
		(4 "In1.Cu" signal "GND")
		(6 "In2.Cu" signal "IN1")
		(8 "In3.Cu" signal "GND1")
		(10 "In4.Cu" signal "IN2")
		(12 "In5.Cu" signal "GND2")
		(14 "In6.Cu" signal "IN3")
		(16 "In7.Cu" signal "GND3")
		(18 "In8.Cu" signal "VCC")
		(20 "In9.Cu" signal "VCC1")
		(22 "In10.Cu" signal "GND4")
		(24 "In11.Cu" signal "IN4")
		(26 "In12.Cu" signal "GND5")
		(28 "In13.Cu" signal "IN5")
		(30 "In14.Cu" signal "GND6")
		(32 "In15.Cu" signal "IN6")
		(34 "In16.Cu" signal "GND7")
		(2 "B.Cu" signal "BOTTOM")
		(9 "F.Adhes" user "F.Adhesive")
		(11 "B.Adhes" user "B.Adhesive")
		(13 "F.Paste" user "Package Geometry/Pastemask Top")
		(15 "B.Paste" user "Package Geometry/Pastemask Bottom")
		(5 "F.SilkS" user "Ref Des/Silkscreen Top")
		(7 "B.SilkS" user "Ref Des/Silkscreen Bottom")
		(1 "F.Mask" user "Board Geometry/Soldermask Top")
		(3 "B.Mask" user "Board Geometry/Soldermask Bottom")
		(17 "Dwgs.User" user "User.Drawings")
		(19 "Cmts.User" user "User.Comments")
		(21 "Eco1.User" user "User.Eco1")
		(23 "Eco2.User" user "User.Eco2")
		(25 "Edge.Cuts" user "Board Geometry/Outline")
		(27 "Margin" user)
		(31 "F.CrtYd" user "Package Geometry/Place Bound Top")
		(29 "B.CrtYd" user "Package Geometry/Place Bound Bottom")
		(35 "F.Fab" user "Ref Des/Assembly Top")
		(33 "B.Fab" user "Ref Des/Assembly Bottom")
	)
	(footprint ""
		(layer "B.Cu")
		(at 355.617272 -261.747762 90)
		(property "Reference" "C2615"
			(at 0 0 90)
			(layer "B.SilkS")
			(hide yes)
			(effects
				(font
					(size 1.27 1.27)
				)
				(justify mirror)
			)
		)
		(property "Value" ""
			(at 0 0 90)
			(layer "B.Fab")
			(effects
				(font
					(size 1.27 1.27)
				)
				(justify mirror)
			)
		)
		(duplicate_pad_numbers_are_jumpers no)
		(fp_line
			(start 0.7874 -0.4064)
			(end -0.7874 -0.4064)
			(stroke
				(width 0.1524)
				(type default)
			)
			(layer "B.SilkS")
		)
		(fp_line
			(start -0.7874 -0.4064)
			(end -0.7874 0.4064)
			(stroke
				(width 0.1524)
				(type default)
			)
			(layer "B.SilkS")
		)
		(fp_line
			(start 0.7874 0.4064)
			(end 0.7874 -0.4064)
			(stroke
				(width 0.1524)
				(type default)
			)
			(layer "B.SilkS")
		)
		(fp_line
			(start -0.7874 0.4064)
			(end 0.7874 0.4064)
			(stroke
				(width 0.1524)
				(type default)
			)
			(layer "B.SilkS")
		)
		(fp_line
			(start 0.67945 -0.305054)
			(end 0.12065 -0.305054)
			(stroke
				(width 0.1)
				(type default)
			)
			(layer "B.Fab")
		)
		(fp_line
			(start 0.12065 -0.305054)
			(end 0.12065 -0.2794)
			(stroke
				(width 0.1)
				(type default)
			)
			(layer "B.Fab")
		)
		(fp_line
			(start -0.12065 -0.3048)
			(end -0.67945 -0.3048)
			(stroke
				(width 0.1)
				(type default)
			)
			(layer "B.Fab")
		)
		(fp_line
			(start -0.67945 -0.3048)
			(end -0.67945 0.3048)
			(stroke
				(width 0.1)
				(type default)
			)
			(layer "B.Fab")
		)
		(fp_line
			(start 0.12065 -0.2794)
			(end -0.12065 -0.2794)
			(stroke
				(width 0.1)
				(type default)
			)
			(layer "B.Fab")
		)
		(fp_line
			(start -0.12065 -0.2794)
			(end -0.12065 -0.3048)
			(stroke
				(width 0.1)
				(type default)
			)
			(layer "B.Fab")
		)
		(fp_line
			(start 0.12065 0.2794)
			(end 0.12065 0.3048)
			(stroke
				(width 0.1)
				(type default)
			)
			(layer "B.Fab")
		)
		(fp_line
			(start -0.120396 0.2794)
			(end 0.12065 0.2794)
			(stroke
				(width 0.1)
				(type default)
			)
			(layer "B.Fab")
		)
		(fp_line
			(start 0.67945 0.3048)
			(end 0.67945 -0.305054)
			(stroke
				(width 0.1)
				(type default)
			)
			(layer "B.Fab")
		)
		(fp_line
			(start 0.12065 0.3048)
			(end 0.67945 0.3048)
			(stroke
				(width 0.1)
				(type default)
			)
			(layer "B.Fab")
		)
		(fp_line
			(start -0.120396 0.3048)
			(end -0.120396 0.2794)
			(stroke
				(width 0.1)
				(type default)
			)
			(layer "B.Fab")
		)
		(fp_line
			(start -0.67945 0.3048)
			(end -0.120396 0.3048)
			(stroke
				(width 0.1)
				(type default)
			)
			(layer "B.Fab")
		)
		(pad "1" smd circle
			(at 0.40005 0 270)
			(size 0 0)
			(layers "B.Cu" "B.Mask" "B.Paste")
			(net "PVDD11_S3_P0")
		)
		(pad "2" smd circle
			(at -0.40005 0 270)
			(size 0 0)
			(layers "B.Cu" "B.Mask" "B.Paste")
			(net "GND")
		)
	)
	(footprint ""
		(layer "B.Cu")
		(at 108.117386 -251.781564)
		(property "Reference" "C2438"
			(at 0 0 0)
			(layer "B.SilkS")
			(hide yes)
			(effects
				(font
					(size 1.27 1.27)
				)
				(justify mirror)
			)
		)
		(property "Value" ""
			(at 0 0 0)
			(layer "B.Fab")
			(effects
				(font
					(size 1.27 1.27)
				)
				(justify mirror)
			)
		)
		(duplicate_pad_numbers_are_jumpers no)
		(fp_line
			(start -0.7874 -0.4064)
			(end -0.7874 0.4064)
			(stroke
				(width 0.1524)
				(type default)
			)
			(layer "B.SilkS")
		)
		(fp_line
			(start -0.7874 0.4064)
			(end 0.7874 0.4064)
			(stroke
				(width 0.1524)
				(type default)
			)
			(layer "B.SilkS")
		)
		(fp_line
			(start 0.7874 -0.4064)
			(end -0.7874 -0.4064)
			(stroke
				(width 0.1524)
				(type default)
			)
			(layer "B.SilkS")
		)
		(fp_line
			(start 0.7874 0.4064)
			(end 0.7874 -0.4064)
			(stroke
				(width 0.1524)
				(type default)
			)
			(layer "B.SilkS")
		)
		(fp_line
			(start -0.67945 -0.3048)
			(end -0.67945 0.3048)
			(stroke
				(width 0.1)
				(type default)
			)
			(layer "B.Fab")
		)
		(fp_line
			(start -0.67945 0.3048)
			(end -0.120396 0.3048)
			(stroke
				(width 0.1)
				(type default)
			)
			(layer "B.Fab")
		)
		(fp_line
			(start -0.12065 -0.3048)
			(end -0.67945 -0.3048)
			(stroke
				(width 0.1)
				(type default)
			)
			(layer "B.Fab")
		)
		(fp_line
			(start -0.12065 -0.2794)
			(end -0.12065 -0.3048)
			(stroke
				(width 0.1)
				(type default)
			)
			(layer "B.Fab")
		)
		(fp_line
			(start -0.120396 0.2794)
			(end 0.12065 0.2794)
			(stroke
				(width 0.1)
				(type default)
			)
			(layer "B.Fab")
		)
		(fp_line
			(start -0.120396 0.3048)
			(end -0.120396 0.2794)
			(stroke
				(width 0.1)
				(type default)
			)
			(layer "B.Fab")
		)
		(fp_line
			(start 0.12065 -0.305054)
			(end 0.12065 -0.2794)
			(stroke
				(width 0.1)
				(type default)
			)
			(layer "B.Fab")
		)
		(fp_line
			(start 0.12065 -0.2794)
			(end -0.12065 -0.2794)
			(stroke
				(width 0.1)
				(type default)
			)
			(layer "B.Fab")
		)
		(fp_line
			(start 0.12065 0.2794)
			(end 0.12065 0.3048)
			(stroke
				(width 0.1)
				(type default)
			)
			(layer "B.Fab")
		)
		(fp_line
			(start 0.12065 0.3048)
			(end 0.67945 0.3048)
			(stroke
				(width 0.1)
				(type default)
			)
			(layer "B.Fab")
		)
		(fp_line
			(start 0.67945 -0.305054)
			(end 0.12065 -0.305054)
			(stroke
				(width 0.1)
				(type default)
			)
			(layer "B.Fab")
		)
		(fp_line
			(start 0.67945 0.3048)
			(end 0.67945 -0.305054)
			(stroke
				(width 0.1)
				(type default)
			)
			(layer "B.Fab")
		)
		(pad "1" smd circle
			(at 0.40005 0 180)
			(size 0 0)
			(layers "B.Cu" "B.Mask" "B.Paste")
			(net "PVDDCR_SOC_P1")
		)
		(pad "2" smd circle
			(at -0.40005 0 180)
			(size 0 0)
			(layers "B.Cu" "B.Mask" "B.Paste")
			(net "GND")
		)
	)
	(footprint ""
		(layer "B.Cu")
		(at 452.62546 -10.60577 90)
		(property "Reference" "R8420"
			(at 0 0 90)
			(layer "B.SilkS")
			(hide yes)
			(effects
				(font
					(size 1.27 1.27)
				)
				(justify mirror)
			)
		)
		(property "Value" ""
			(at 0 0 90)
			(layer "B.Fab")
			(effects
				(font
					(size 1.27 1.27)
				)
				(justify mirror)
			)
		)
		(duplicate_pad_numbers_are_jumpers no)
		(fp_line
			(start 0.7874 -0.4064)
			(end -0.7874 -0.4064)
			(stroke
				(width 0.1524)
				(type default)
			)
			(layer "B.SilkS")
		)
		(fp_line
			(start -0.7874 -0.4064)
			(end -0.7874 0.4064)
			(stroke
				(width 0.1524)
				(type default)
			)
			(layer "B.SilkS")
		)
		(fp_line
			(start 0.7874 0.4064)
			(end 0.7874 -0.4064)
			(stroke
				(width 0.1524)
				(type default)
			)
			(layer "B.SilkS")
		)
		(fp_line
			(start -0.7874 0.4064)
			(end 0.7874 0.4064)
			(stroke
				(width 0.1524)
				(type default)
			)
			(layer "B.SilkS")
		)
		(fp_line
			(start 0.67945 -0.305054)
			(end 0.12065 -0.305054)
			(stroke
				(width 0.1)
				(type default)
			)
			(layer "B.Fab")
		)
		(fp_line
			(start 0.12065 -0.305054)
			(end 0.12065 -0.2794)
			(stroke
				(width 0.1)
				(type default)
			)
			(layer "B.Fab")
		)
		(fp_line
			(start -0.12065 -0.3048)
			(end -0.67945 -0.3048)
			(stroke
				(width 0.1)
				(type default)
			)
			(layer "B.Fab")
		)
		(fp_line
			(start -0.67945 -0.3048)
			(end -0.67945 0.3048)
			(stroke
				(width 0.1)
				(type default)
			)
			(layer "B.Fab")
		)
		(fp_line
			(start 0.12065 -0.2794)
			(end -0.12065 -0.2794)
			(stroke
				(width 0.1)
				(type default)
			)
			(layer "B.Fab")
		)
		(fp_line
			(start -0.12065 -0.2794)
			(end -0.12065 -0.3048)
			(stroke
				(width 0.1)
				(type default)
			)
			(layer "B.Fab")
		)
		(fp_line
			(start 0.12065 0.2794)
			(end 0.12065 0.3048)
			(stroke
				(width 0.1)
				(type default)
			)
			(layer "B.Fab")
		)
		(fp_line
			(start -0.120396 0.2794)
			(end 0.12065 0.2794)
			(stroke
				(width 0.1)
				(type default)
			)
			(layer "B.Fab")
		)
		(fp_line
			(start 0.67945 0.3048)
			(end 0.67945 -0.305054)
			(stroke
				(width 0.1)
				(type default)
			)
			(layer "B.Fab")
		)
		(fp_line
			(start 0.12065 0.3048)
			(end 0.67945 0.3048)
			(stroke
				(width 0.1)
				(type default)
			)
			(layer "B.Fab")
		)
		(fp_line
			(start -0.120396 0.3048)
			(end -0.120396 0.2794)
			(stroke
				(width 0.1)
				(type default)
			)
			(layer "B.Fab")
		)
		(fp_line
			(start -0.67945 0.3048)
			(end -0.120396 0.3048)
			(stroke
				(width 0.1)
				(type default)
			)
			(layer "B.Fab")
		)
		(pad "1" smd circle
			(at 0.40005 0 270)
			(size 0 0)
			(layers "B.Cu" "B.Mask" "B.Paste")
			(net "SGPIO_OCP_SFF_LD_N")
		)
		(pad "2" smd circle
			(at -0.40005 0 270)
			(size 0 0)
			(layers "B.Cu" "B.Mask" "B.Paste")
			(net "P3V3_OCP_SFF")
		)
	)
	(footprint ""
		(layer "B.Cu")
		(at 183.045608 -126.833376 90)
		(property "Reference" "R1278"
			(at 0 0 90)
			(layer "B.SilkS")
			(hide yes)
			(effects
				(font
					(size 1.27 1.27)
				)
				(justify mirror)
			)
		)
		(property "Value" ""
			(at 0 0 90)
			(layer "B.Fab")
			(effects
				(font
					(size 1.27 1.27)
				)
				(justify mirror)
			)
		)
		(duplicate_pad_numbers_are_jumpers no)
		(fp_line
			(start 0.7874 -0.4064)
			(end -0.7874 -0.4064)
			(stroke
				(width 0.1524)
				(type default)
			)
			(layer "B.SilkS")
		)
		(fp_line
			(start -0.7874 -0.4064)
			(end -0.7874 0.4064)
			(stroke
				(width 0.1524)
				(type default)
			)
			(layer "B.SilkS")
		)
		(fp_line
			(start 0.7874 0.4064)
			(end 0.7874 -0.4064)
			(stroke
				(width 0.1524)
				(type default)
			)
			(layer "B.SilkS")
		)
		(fp_line
			(start -0.7874 0.4064)
			(end 0.7874 0.4064)
			(stroke
				(width 0.1524)
				(type default)
			)
			(layer "B.SilkS")
		)
		(fp_line
			(start 0.67945 -0.305054)
			(end 0.12065 -0.305054)
			(stroke
				(width 0.1)
				(type default)
			)
			(layer "B.Fab")
		)
		(fp_line
			(start 0.12065 -0.305054)
			(end 0.12065 -0.2794)
			(stroke
				(width 0.1)
				(type default)
			)
			(layer "B.Fab")
		)
		(fp_line
			(start -0.12065 -0.3048)
			(end -0.67945 -0.3048)
			(stroke
				(width 0.1)
				(type default)
			)
			(layer "B.Fab")
		)
		(fp_line
			(start -0.67945 -0.3048)
			(end -0.67945 0.3048)
			(stroke
				(width 0.1)
				(type default)
			)
			(layer "B.Fab")
		)
		(fp_line
			(start 0.12065 -0.2794)
			(end -0.12065 -0.2794)
			(stroke
				(width 0.1)
				(type default)
			)
			(layer "B.Fab")
		)
		(fp_line
			(start -0.12065 -0.2794)
			(end -0.12065 -0.3048)
			(stroke
				(width 0.1)
				(type default)
			)
			(layer "B.Fab")
		)
		(fp_line
			(start 0.12065 0.2794)
			(end 0.12065 0.3048)
			(stroke
				(width 0.1)
				(type default)
			)
			(layer "B.Fab")
		)
		(fp_line
			(start -0.120396 0.2794)
			(end 0.12065 0.2794)
			(stroke
				(width 0.1)
				(type default)
			)
			(layer "B.Fab")
		)
		(fp_line
			(start 0.67945 0.3048)
			(end 0.67945 -0.305054)
			(stroke
				(width 0.1)
				(type default)
			)
			(layer "B.Fab")
		)
		(fp_line
			(start 0.12065 0.3048)
			(end 0.67945 0.3048)
			(stroke
				(width 0.1)
				(type default)
			)
			(layer "B.Fab")
		)
		(fp_line
			(start -0.120396 0.3048)
			(end -0.120396 0.2794)
			(stroke
				(width 0.1)
				(type default)
			)
			(layer "B.Fab")
		)
		(fp_line
			(start -0.67945 0.3048)
			(end -0.120396 0.3048)
			(stroke
				(width 0.1)
				(type default)
			)
			(layer "B.Fab")
		)
		(pad "1" smd circle
			(at 0.40005 0 270)
			(size 0 0)
			(layers "B.Cu" "B.Mask" "B.Paste")
			(net "FM_P1_PCC0_N")
		)
		(pad "2" smd circle
			(at -0.40005 0 270)
			(size 0 0)
			(layers "B.Cu" "B.Mask" "B.Paste")
			(net "FM_P1_PCC0_R_N")
		)
	)
	(footprint ""
		(layer "B.Cu")
		(at 407.946098 -396.393162 -90)
		(property "Reference" "C791"
			(at 0 0 90)
			(layer "B.SilkS")
			(hide yes)
			(effects
				(font
					(size 1.27 1.27)
				)
				(justify mirror)
			)
		)
		(property "Value" ""
			(at 0 0 90)
			(layer "B.Fab")
			(effects
				(font
					(size 1.27 1.27)
				)
				(justify mirror)
			)
		)
		(duplicate_pad_numbers_are_jumpers no)
		(fp_line
			(start -0.299974 0.150114)
			(end 0.299974 0.150114)
			(stroke
				(width 0.1)
				(type default)
			)
			(layer "B.Fab")
		)
		(fp_line
			(start 0.299974 0.150114)
			(end 0.299974 -0.150114)
			(stroke
				(width 0.1)
				(type default)
			)
			(layer "B.Fab")
		)
		(fp_line
			(start -0.299974 -0.150114)
			(end -0.299974 0.150114)
			(stroke
				(width 0.1)
				(type default)
			)
			(layer "B.Fab")
		)
		(fp_line
			(start 0.299974 -0.150114)
			(end -0.299974 -0.150114)
			(stroke
				(width 0.1)
				(type default)
			)
			(layer "B.Fab")
		)
		(pad "1" smd rect
			(at 0.2667 0 90)
			(size 0.3048 0.381)
			(layers "B.Cu" "B.Mask" "B.Paste")
			(net "P0V9_CPU0_RT2_2A_2D")
		)
		(pad "2" smd rect
			(at -0.2667 0 90)
			(size 0.3048 0.381)
			(layers "B.Cu" "B.Mask" "B.Paste")
			(net "GND")
		)
	)
	(footprint ""
		(layer "B.Cu")
		(at 114.033046 -267.529564)
		(property "Reference" "C2388"
			(at 0 0 0)
			(layer "B.SilkS")
			(hide yes)
			(effects
				(font
					(size 1.27 1.27)
				)
				(justify mirror)
			)
		)
		(property "Value" ""
			(at 0 0 0)
			(layer "B.Fab")
			(effects
				(font
					(size 1.27 1.27)
				)
				(justify mirror)
			)
		)
		(duplicate_pad_numbers_are_jumpers no)
		(fp_line
			(start -0.7874 -0.4064)
			(end -0.7874 0.4064)
			(stroke
				(width 0.1524)
				(type default)
			)
			(layer "B.SilkS")
		)
		(fp_line
			(start -0.7874 0.4064)
			(end 0.7874 0.4064)
			(stroke
				(width 0.1524)
				(type default)
			)
			(layer "B.SilkS")
		)
		(fp_line
			(start 0.7874 -0.4064)
			(end -0.7874 -0.4064)
			(stroke
				(width 0.1524)
				(type default)
			)
			(layer "B.SilkS")
		)
		(fp_line
			(start 0.7874 0.4064)
			(end 0.7874 -0.4064)
			(stroke
				(width 0.1524)
				(type default)
			)
			(layer "B.SilkS")
		)
		(fp_line
			(start -0.67945 -0.3048)
			(end -0.67945 0.3048)
			(stroke
				(width 0.1)
				(type default)
			)
			(layer "B.Fab")
		)
		(fp_line
			(start -0.67945 0.3048)
			(end -0.120396 0.3048)
			(stroke
				(width 0.1)
				(type default)
			)
			(layer "B.Fab")
		)
		(fp_line
			(start -0.12065 -0.3048)
			(end -0.67945 -0.3048)
			(stroke
				(width 0.1)
				(type default)
			)
			(layer "B.Fab")
		)
		(fp_line
			(start -0.12065 -0.2794)
			(end -0.12065 -0.3048)
			(stroke
				(width 0.1)
				(type default)
			)
			(layer "B.Fab")
		)
		(fp_line
			(start -0.120396 0.2794)
			(end 0.12065 0.2794)
			(stroke
				(width 0.1)
				(type default)
			)
			(layer "B.Fab")
		)
		(fp_line
			(start -0.120396 0.3048)
			(end -0.120396 0.2794)
			(stroke
				(width 0.1)
				(type default)
			)
			(layer "B.Fab")
		)
		(fp_line
			(start 0.12065 -0.305054)
			(end 0.12065 -0.2794)
			(stroke
				(width 0.1)
				(type default)
			)
			(layer "B.Fab")
		)
		(fp_line
			(start 0.12065 -0.2794)
			(end -0.12065 -0.2794)
			(stroke
				(width 0.1)
				(type default)
			)
			(layer "B.Fab")
		)
		(fp_line
			(start 0.12065 0.2794)
			(end 0.12065 0.3048)
			(stroke
				(width 0.1)
				(type default)
			)
			(layer "B.Fab")
		)
		(fp_line
			(start 0.12065 0.3048)
			(end 0.67945 0.3048)
			(stroke
				(width 0.1)
				(type default)
			)
			(layer "B.Fab")
		)
		(fp_line
			(start 0.67945 -0.305054)
			(end 0.12065 -0.305054)
			(stroke
				(width 0.1)
				(type default)
			)
			(layer "B.Fab")
		)
		(fp_line
			(start 0.67945 0.3048)
			(end 0.67945 -0.305054)
			(stroke
				(width 0.1)
				(type default)
			)
			(layer "B.Fab")
		)
		(pad "1" smd circle
			(at 0.40005 0 180)
			(size 0 0)
			(layers "B.Cu" "B.Mask" "B.Paste")
			(net "PVDDCR_CPU1_P1")
		)
		(pad "2" smd circle
			(at -0.40005 0 180)
			(size 0 0)
			(layers "B.Cu" "B.Mask" "B.Paste")
			(net "GND")
		)
	)
	(footprint ""
		(layer "B.Cu")
		(at 115.595146 -30.481778)
		(property "Reference" "C6118"
			(at 0 0 0)
			(layer "B.SilkS")
			(hide yes)
			(effects
				(font
					(size 1.27 1.27)
				)
				(justify mirror)
			)
		)
		(property "Value" ""
			(at 0 0 0)
			(layer "B.Fab")
			(effects
				(font
					(size 1.27 1.27)
				)
				(justify mirror)
			)
		)
		(duplicate_pad_numbers_are_jumpers no)
		(fp_line
			(start -1.524 -0.762)
			(end -1.524 0.762)
			(stroke
				(width 0.1524)
				(type default)
			)
			(layer "B.SilkS")
		)
		(fp_line
			(start -1.524 0.762)
			(end 1.524 0.762)
			(stroke
				(width 0.1524)
				(type default)
			)
			(layer "B.SilkS")
		)
		(fp_line
			(start 1.524 -0.762)
			(end -1.524 -0.762)
			(stroke
				(width 0.1524)
				(type default)
			)
			(layer "B.SilkS")
		)
		(fp_line
			(start 1.524 0.762)
			(end 1.524 -0.762)
			(stroke
				(width 0.1524)
				(type default)
			)
			(layer "B.SilkS")
		)
		(fp_line
			(start -1.1049 -0.724916)
			(end 1.1049 -0.724916)
			(stroke
				(width 0.1)
				(type default)
			)
			(layer "B.Fab")
		)
		(fp_line
			(start -1.1049 0.724916)
			(end -1.1049 -0.724916)
			(stroke
				(width 0.1)
				(type default)
			)
			(layer "B.Fab")
		)
		(fp_line
			(start 1.1049 -0.724916)
			(end 1.1049 0.724916)
			(stroke
				(width 0.1)
				(type default)
			)
			(layer "B.Fab")
		)
		(fp_line
			(start 1.1049 0.724916)
			(end -1.1049 0.724916)
			(stroke
				(width 0.1)
				(type default)
			)
			(layer "B.Fab")
		)
		(pad "1" smd rect
			(at 0.889 0)
			(size 1.016 1.27)
			(layers "B.Cu" "B.Mask" "B.Paste")
			(net "P1V2_CPU0_USB2_DVDD12")
		)
		(pad "2" smd rect
			(at -0.889 0)
			(size 1.016 1.27)
			(layers "B.Cu" "B.Mask" "B.Paste")
			(net "GND")
		)
	)
)
